5
5
4
4
3
3
2
2
1
1
D D
C C
B B
A A
Version:  1
Project Code: BPD00Q010001
PCB P/N:
Layer:    8Layers
M.2 Adaptor Card
Lightning 
15750
Title 
Size Document Number Rev
Date: Sheet 
of 
Lightning_M.2_Adaptor_Card 1
COVER_PAGE_1 
A3 
1 10 Thursday, March 09, 2017 
Wiwynn 
H/W R&D Dept. II 
8F, 90, Sec.1, Xintai 5th Rd., Xizhi Dist.,
New Taipei City 22102, Taiwan (R.O.C.)
Title 
Size Document Number Rev
Date: Sheet 
of 
Lightning_M.2_Adaptor_Card 1
COVER_PAGE_1 
A3 
1 10 Thursday, March 09, 2017 
Wiwynn 
H/W R&D Dept. II 
8F, 90, Sec.1, Xintai 5th Rd., Xizhi Dist.,
New Taipei City 22102, Taiwan (R.O.C.)
Title 
Size Document Number Rev
Date: Sheet 
of 
Lightning_M.2_Adaptor_Card 1
COVER_PAGE_1 
A3 
1 10 Thursday, March 09, 2017 
Wiwynn 
H/W R&D Dept. II 
8F, 90, Sec.1, Xintai 5th Rd., Xizhi Dist.,
New Taipei City 22102, Taiwan (R.O.C.)



5
5
4
4
3
3
2
2
1
1
D D
C C
B B
A A
LIGHTNING M.2 ADAPTOR CARD 
Approvals 
DESCRIPTION Reviewer DATE REV 
Contents 
NET NAME 
<Routing Class>_<Main-domain>_<Port>_<Sub-domain>_<{#}Signal Name{DP/DN}> 
Note that <Field> is ,andatory field, wheraeas {Field} is optional field 
Field : Description on Field : 
Routing Class : Define the impedance, single end 
or differential, and the length tolerance to the net 
D85: 85 ohm impedance of differentail end signals 
Main-domain:BMC and SOC's specific interface 
PCIE : PCIE bus 
TX: Transmitter signal 
RX: Receiver signal 
{#} Signal Name{DP/DN} : '#' only for low-active signals 
 'DP/DN' only for differentail pairs 
Z50: 50 ohm impedance of single end signals 
SMB:SMBus 
TEMP:Temperature Sensor 
Sub-domain:BMC and SOC's specific interface 
Port:Device Name 
A:A Port(PCIe Port0 and Port1 from 8639) 
B:B Port(PCIe Port2 and Port3 from 8639) 
First review 0.1 2016/11/16 <name> 
2016/12/29 0.2 Second review <name> 
Title 
Size Document Number Rev
Date: Sheet 
of 
Lightning_M.2_Adaptor_Card 1
COVER PAGE_2 
A3 
2 10 Thursday, March 09, 2017 
Wiwynn 
H/W R&D Dept. II 
8F,90,Sec. 1,Hsin Tai Wu Rd, 
New Taipei City 22102, Taiwan (R.O.C.)
Title 
Size Document Number Rev
Date: Sheet 
of 
Lightning_M.2_Adaptor_Card 1
COVER PAGE_2 
A3 
2 10 Thursday, March 09, 2017 
Wiwynn 
H/W R&D Dept. II 
8F,90,Sec. 1,Hsin Tai Wu Rd, 
New Taipei City 22102, Taiwan (R.O.C.)
Title 
Size Document Number Rev
Date: Sheet 
of 
Lightning_M.2_Adaptor_Card 1
COVER PAGE_2 
A3 
2 10 Thursday, March 09, 2017 
Wiwynn 
H/W R&D Dept. II 
8F,90,Sec. 1,Hsin Tai Wu Rd, 
New Taipei City 22102, Taiwan (R.O.C.)



5
5
4
4
3
3
2
2
1
1
D D
C C
B B
A A
Title 
Size Document Number Rev
Date: Sheet 
of 
Lightning_M.2_Adaptor_Card 1
BLOCK DIAGRAM 
A3 
3 10 Thursday, March 09, 2017 
Wiwynn 
H/W R&D Dept. II 
8F, 90, Sec.1, Xintai 5th Rd., Xizhi Dist.,
New Taipei City 22102, Taiwan (R.O.C.)
Title 
Size Document Number Rev
Date: Sheet 
of 
Lightning_M.2_Adaptor_Card 1
BLOCK DIAGRAM 
A3 
3 10 Thursday, March 09, 2017 
Wiwynn 
H/W R&D Dept. II 
8F, 90, Sec.1, Xintai 5th Rd., Xizhi Dist.,
New Taipei City 22102, Taiwan (R.O.C.)
Title 
Size Document Number Rev
Date: Sheet 
of 
Lightning_M.2_Adaptor_Card 1
BLOCK DIAGRAM 
A3 
3 10 Thursday, March 09, 2017 
Wiwynn 
H/W R&D Dept. II 
8F, 90, Sec.1, Xintai 5th Rd., Xizhi Dist.,
New Taipei City 22102, Taiwan (R.O.C.)



5
5
4
4
3
3
2
2
1
1
D D
C C
B B
A A
03 04 05 0802 0706 0901
TABLE OF CONTENTS
PAGE TITLE PAGE
PAGE
PAGE TITLE
562R2F- GP 
562 = 562 ohm, (2K2R means 2.2K ohm) 
2 = size 0402 
F = 1% tolerance 
GP= Green Part (RoHS) 
Wiwynn RC size code as below: 
1 = 0201 
2= 0402 
3= 0603 
5= 0805 
6= 1206 
Wiwynn R tolerance code as below: 
D=0.5% 
F= 1% 
J= 5% 
SCD1U10V2KX-5GP 
D1U = 0.1uF (2D2U means 2.2uF) 
10Voltage (6D3V means 6.3V) 
2 = size 0402, K tolerance 
K=tolerance 
[Wiwynn C code as below:] 
G=2% 
J=5% 
K=10% 
M=20% 
X=temp characteristics 
[Wiwynn C Series/Temp] 
N=NPO 
X=X7R/X5R 
Y=Y5V 
-5=different symbol/customer 
GP= Green Part (RoHS) 
COVER PAGE(1/2)TABLE OF CONTENTSPCIe ConnectorM.2 ConnectorCOVER PAGE(2/2)P3V3_PWRI2C DeviceBLOCK DIAGRAM Change List
010
P1V8_PWR
011 Change List
Title 
Size Document Number Rev
Date: Sheet 
of 
Lightning_M.2_Adaptor_Card 1
TABLE OF CONTENTS 
A3 
4 10 Thursday, March 09, 2017 
Wiwynn 
H/W R&D Dept. II 
8F,90,Sec. 1,Hsin Tai Wu Rd, 
New Taipei City 22102, Taiwan (R.O.C.)
Title 
Size Document Number Rev
Date: Sheet 
of 
Lightning_M.2_Adaptor_Card 1
TABLE OF CONTENTS 
A3 
4 10 Thursday, March 09, 2017 
Wiwynn 
H/W R&D Dept. II 
8F,90,Sec. 1,Hsin Tai Wu Rd, 
New Taipei City 22102, Taiwan (R.O.C.)
Title 
Size Document Number Rev
Date: Sheet 
of 
Lightning_M.2_Adaptor_Card 1
TABLE OF CONTENTS 
A3 
4 10 Thursday, March 09, 2017 
Wiwynn 
H/W R&D Dept. II 
8F,90,Sec. 1,Hsin Tai Wu Rd, 
New Taipei City 22102, Taiwan (R.O.C.)



5
5
4
4
3
3
2
2
1
1
D D
C C
B B
A A
P12V 
P3V3_DPB 
D85_PCIE_B_REFCLK_P 6
D85_PCIE_B_REFCLK_N 6
Z50_SSD_ACT# 6
D85_PCIE_A_REFCLK_P 6
D85_PCIE_A_REFCLK_N 6
Z50_SSD_M2_PRSNT# 6
Z50_DEV_RST# 6
Z50_SSD_M2_PRSNT# 6
Z50_SMB_DATA 7
Z50_SMB_CLK 7
D85_PCIE_A_TX0_N 6
D85_PCIE_A_TX0_P 6
D85_PCIE_A_RX0_N 6
D85_PCIE_A_RX0_P 6
D85_PCIE_A_RX1_N 6
D85_PCIE_A_RX1_P 6
D85_PCIE_B_RX0_N 6
D85_PCIE_B_RX0_P 6
D85_PCIE_B_RX1_N 6
D85_PCIE_B_RX1_P 6
D85_PCIE_A_TX1_N 6
D85_PCIE_A_TX1_P 6
D85_PCIE_B_TX0_N 6
D85_PCIE_B_TX0_P 6
D85_PCIE_B_TX1_N 6
D85_PCIE_B_TX1_P 6
Title 
Size Document Number Rev
Date: Sheet 
of 
Lightning_M.2_Adaptor_Card 1
PCIe Connector 
A2 
5 10 Thursday, March 09, 2017 
Wiwynn 
H/W R&D Dept. II 
8F, 90, Sec.1, Xintai 5th Rd., Xizhi Dist.,
New Taipei City 22102, Taiwan (R.O.C.)
Title 
Size Document Number Rev
Date: Sheet 
of 
Lightning_M.2_Adaptor_Card 1
PCIe Connector 
A2 
5 10 Thursday, March 09, 2017 
Wiwynn 
H/W R&D Dept. II 
8F, 90, Sec.1, Xintai 5th Rd., Xizhi Dist.,
New Taipei City 22102, Taiwan (R.O.C.)
Title 
Size Document Number Rev
Date: Sheet 
of 
Lightning_M.2_Adaptor_Card 1
PCIe Connector 
A2 
5 10 Thursday, March 09, 2017 
Wiwynn 
H/W R&D Dept. II 
8F, 90, Sec.1, Xintai 5th Rd., Xizhi Dist.,
New Taipei City 22102, Taiwan (R.O.C.)
H3 
HOLE315R140-GP 
1
H2 
HOLE315R140-GP 
1
H1 
HOLE315R140-GP 
1
SKT1 
SKT-SAS28-P15-PCIE25-2-GP 
S1 
S2 
S3 
S4 
S5 
S6 
S7 
S8 
S9 
S10 
S11 
S12 
S13 
S14 
S15 
S16 
S17 
S18 
S19 
S20 
S21 
S22 
S23 
S24 
S25 
S26 
S27 
S28 
E1 
E2 
E3 
E4 
E5 
E6 
P1 
P2 
P3 
P4 
P5 
P6 
P7 
P8 
P9 
P10 
P11 
P12 
P13 
P14 
P15 
E7 
E8 
E9 
E10 
E11 
E12 
E13 
E14 
E15 
E16 
E17 
E18 
E19 
E20 
E21 
E22 
E23 
E24 
E25 
G1 
G2 
NP1 
NP2 
C43 
SC1U16V3KX-5GP 
1 2



5
5
4
4
3
3
2
2
1
1
D D
C C
B B
A A
Z50_SSD_A_R_ACT# 
Z50_SSD_A_PRESENT_R# Z50_SSD_A_PRSNT# 
Z50_SSD_B_PRESENT_R# Z50_SSD_B_PRSNT# 
Z50_SSD_B_ACT# 
Z50_SSD_A1_ALERT# 
Z50_SSD_B1_ALERT# 
Z50_SSD_B1_CLKREQ# 
Z50_SSD_A1_CLKREQ# 
Z50_SSD_A_PRSNT# 
Z50_SSD_B_PRSNT# 
Z50_SSD_B_R_ACT# Z50_SSD_B_ACT# 
Z50_SSD_A_ACT# 
Z50_SSD_A_ACT# 
SSD_A1_MFG_CLK_TP 
SSD_A1_MFG_DATA_TP 
SSD_B1_MFG_CLK_TP 
SSD_B1_MFG_DATA_TP 
P3V3_PWR 
P3V3_PWR 
P3V3_PWR 
P3V3_PWR 
P3V3_DPB P3V3_DPB P3V3_DPB 
P1V8_PWR 
P1V8_PWR P3V3_PWR 
P3V3_PWR 
P3V3_DPB P3V3_DPB P3V3_DPB 
D85_PCIE_A_REFCLK_P 5
D85_PCIE_A_REFCLK_N 5
D85_PCIE_B_REFCLK_P 5
D85_PCIE_B_REFCLK_N 5
Z50_DEV_RST# 5
Z50_DEV_RST# 5
Z50_SSD_ACT# 5
Z50_SSD_A1_SMB_CLK 7
Z50_SSD_A1_SMB_DATA 7
Z50_SSD_B1_SMB_CLK 7
Z50_SSD_B1_SMB_DATA 7
Z50_SSD_M2_PRSNT# 5
D85_PCIE_A_TX0_N 5
D85_PCIE_A_TX0_P 5
D85_PCIE_A_TX1_N 5
D85_PCIE_A_TX1_P 5
D85_PCIE_A_RX0_N 5
D85_PCIE_A_RX0_P 5
D85_PCIE_A_RX1_P 5
D85_PCIE_A_RX1_N 5
D85_PCIE_B_TX0_N 5
D85_PCIE_B_TX0_P 5
D85_PCIE_B_TX1_N 5
D85_PCIE_B_TX1_P 5
D85_PCIE_B_RX0_P 5
D85_PCIE_B_RX0_N 5
D85_PCIE_B_RX1_P 5
D85_PCIE_B_RX1_N 5
Title 
Size Document Number Rev
Date: Sheet 
of 
Lightning_M.2_Adaptor_Card 1
M.2 Connector 
A2 
6 10 Thursday, March 09, 2017 
Wiwynn 
H/W R&D Dept. II 
8F, 90, Sec.1, Xintai 5th Rd., Xizhi Dist.,
New Taipei City 22102, Taiwan (R.O.C.)
Title 
Size Document Number Rev
Date: Sheet 
of 
Lightning_M.2_Adaptor_Card 1
M.2 Connector 
A2 
6 10 Thursday, March 09, 2017 
Wiwynn 
H/W R&D Dept. II 
8F, 90, Sec.1, Xintai 5th Rd., Xizhi Dist.,
New Taipei City 22102, Taiwan (R.O.C.)
Title 
Size Document Number Rev
Date: Sheet 
of 
Lightning_M.2_Adaptor_Card 1
M.2 Connector 
A2 
6 10 Thursday, March 09, 2017 
Wiwynn 
H/W R&D Dept. II 
8F, 90, Sec.1, Xintai 5th Rd., Xizhi Dist.,
New Taipei City 22102, Taiwan (R.O.C.)
R23 
47KR2F-GP 1 2
C1 
SC1U6D3V2KX-9-GP 
1 2
C15 
SCD1U16V2KX-3GP 
1 2
C37 
SC1U6D3V2KX-9-GP 
1 2
C41 
SCD1U16V2KX-3GP 
1 2
C2 
SCD1U16V2KX-3GP 
1 2
C38 
SC1U6D3V2KX-9-GP 
1 2
C35 
SC10U6D3V5KX-4GP 
1 2
C18 
SC1U6D3V2KX-9-GP 
1 2
R33 
47KR2F-GP 
12 C3 
SCD1U16V2KX-3GP 
1 2
C36 
SC10U6D3V5KX-4GP 
1 2
C19 
SC1U6D3V2KX-9-GP 
1 2
R48 
47KR2F-GP NOPOP 
1 2
R44 
47KR2F-GP 1 2
SSD_A1 
SKT-MINI75P-11-GP 
76 76 77 77 
NP1 NP1 NP2 NP2 
3_3V 2 3_3V 4 NC#6 6 NC#8 8 DAS/DSS#/LED1# 10 3_3V 12 3_3V 14 3_3V 16 3_3V 18 NC#20 20 NC#22 22 NC#24 24 NC#26 26 NC#28 28 NC#30 30 NC#32 32 NC#34 34 NC#36 36 DEVSLP 38 NC#40 40 NC#42 42 NC#44 44 NC#46 46 NC#48 48 PERST#/NC#50 50 CLKREQ#/NC#52 52 PEWAKE#/NC#54 54 NC#56 56 NC#58 58 
SUSCLK_32KHZ 68 3_3V 70 3_3V 72 3_3V 74 
GND 1GND 3
PETP3 13 
PETN3 11 
GND 9
PERN3 5
GND 15 
GND 21 
PERN2 17 PERP2 19 
GND 27 
GND 33 
PERN1 29 PERP1 31 
GND 39 PERN0/SATA-B+ 41 PERP0/SATA-B- 43 GND 45 PETN0/SATA-A- 47 PETP0/SATA-A+ 49 GND 51 REFCLKN 53 REFCLKP 55 
NC#67 67 PEDET/NC-PCIE/GND-SATA 69 GND 71 GND 73 GND 75 
PETP2 25 
PETN2 23 
PETP1 37 
PETN1 35 
GND 57 
PERP3 7
C31 
SC1U6D3V2KX-9-GP 
1 2
R45 
47KR2F-GP 1 2
TP7 1
R49 
47KR2F-GP NOPOP 
1 2
SSD_B1 
SKT-MINI75P-11-GP 
76 76 77 77 
NP1 NP1 NP2 NP2 
3_3V 2 3_3V 4 NC#6 6 NC#8 8 DAS/DSS#/LED1# 10 3_3V 12 3_3V 14 3_3V 16 3_3V 18 NC#20 20 NC#22 22 NC#24 24 NC#26 26 NC#28 28 NC#30 30 NC#32 32 NC#34 34 NC#36 36 DEVSLP 38 NC#40 40 NC#42 42 NC#44 44 NC#46 46 NC#48 48 PERST#/NC#50 50 CLKREQ#/NC#52 52 PEWAKE#/NC#54 54 NC#56 56 NC#58 58 
SUSCLK_32KHZ 68 3_3V 70 3_3V 72 3_3V 74 
GND 1GND 3
PETP3 13 
PETN3 11 
GND 9
PERN3 5
GND 15 
GND 21 
PERN2 17 PERP2 19 
GND 27 
GND 33 
PERN1 29 PERP1 31 
GND 39 PERN0/SATA-B+ 41 PERP0/SATA-B- 43 GND 45 PETN0/SATA-A- 47 PETP0/SATA-A+ 49 GND 51 REFCLKN 53 REFCLKP 55 
NC#67 67 PEDET/NC-PCIE/GND-SATA 69 GND 71 GND 73 GND 75 
PETP2 25 
PETN2 23 
PETP1 37 
PETN1 35 
GND 57 
PERP3 7
C33 
SCD1U16V2KX-3GP 
1 2
R37 
47KR2F-GP 
12
R14 
0R2J-2-GP 
1 2
U3 
74LVC1G32DC-1GP 
A1
B2
GND 3 Y 4
VCC 5
C42 
SCD1U16V2KX-3GP 
1 2
R4 
0R2J-2-GP 
1 2
C12 
SC1U6D3V2KX-9-GP 
1 2
R43 
4K7R2F-GP 
NOPOP 
1 2
R24 
47KR2F-GP 1 2
R42 
4K7R2F-GP 
NOPOP 
1 2
C21 
SCD1U16V2KX-3GP 
1 2
C14 
SCD1U16V2KX-3GP 
1 2
C16 
SC10U6D3V5KX-4GP 
1 2
U5 
74LVC1G32DC-1GP 
A1
B2
GND 3 Y 4
VCC 5
R46 
47KR2F-GP NOPOP 
1 2
C32 
SCD1U16V2KX-3GP 
1 2
C22 
SCD1U16V2KX-3GP 
1 2
C17 
SC10U6D3V5KX-4GP 
1 2
C20 
SC1U6D3V2KX-9-GP 
1 2
TP6 1
R47 
47KR2F-GP NOPOP 
1 2
C13 
SCD1U16V2KX-3GP 
1 2 R2 
0R2J-2-GP 
1 2
TP8 1
C34 
SCD1U16V2KX-3GP 
1 2
R15 
0R2J-2-GP 
1 2
TP9 1



5
5
4
4
3
3
2
2
1
1
D D
C C
B B
A A
ADD=1001100 (0x98) 
TEMP SENSOR 
SMBus Switch 
ADD=11101110 (0xE6) 
Z50_TEMP_1_ALERT# 
Z50_TEMP_1_A0 
Z50_TEMP_1_CLK 
Z50_TEMP_1_DATA 
Z50_TEMP_1_A2 
Z50_TEMP_1_A1 
Z50_SSD_A1_SMB_DATA 
Z50_SSD_A1_SMB_CLK 
Z50_SSD_B1_SMB_DATA 
Z50_SSD_B1_SMB_CLK 
Z50_SMB_SWITCH_ADDRESS_A0 
Z50_SMB_SWITCH_ADDRESS_A1 
Z50_SMB_CLK 
Z50_SMB_DATA 
Z50_SSD_A1_SMB_DATA_R 
Z50_SSD_A1_SMB_CLK_R 
Z50_SSD_B1_SMB_DATA_R 
Z50_SSD_B1_SMB_CLK_R 
Z50_SMB_SWITCH_ADDRESS_A0 
Z50_SMB_SWITCH_ADDRESS_A1 
Z50_SMB_SWITCH_RESET# 
Z50_SSD_A1_SMB_DATA_LL 
Z50_SSD_A1_SMB_CLK_LL 
Z50_SSD_B1_SMB_CLK_LL 
Z50_SSD_B1_SMB_DATA_LL 
Z50_SSD_B1_SMB_CLK Z50_SSD_B1_SMB_CLK_LL 
Z50_SSD_B1_SMB_DATA_LR 
Z50_SSD_B1_SMB_CLK_LR 
Z50_SSD_B1_SMB_DATA Z50_SSD_B1_SMB_DATA_LL 
SSD_B1_SMB_OE 
Z50_SSD_A1_SMB_CLK Z50_SSD_A1_SMB_CLK_LL 
Z50_SSD_A1_SMB_DATA_LR 
Z50_SSD_A1_SMB_CLK_LR 
Z50_SSD_A1_SMB_DATA Z50_SSD_A1_SMB_DATA_LL 
SSD_A1_SMB_OE 
Z50_SSD_A1_SMB_DATA_R 
Z50_SSD_B1_SMB_DATA_R 
Z50_SSD_A1_SMB_CLK_R 
Z50_SSD_B1_SMB_CLK_R 
Z50_SSD_A1_SMB_DATA_R 
Z50_SSD_B1_SMB_DATA_R 
Z50_SSD_A1_SMB_DATA 
Z50_SSD_B1_SMB_DATA 
Z50_SSD_A1_SMB_CLK_R 
Z50_SSD_B1_SMB_CLK_R 
Z50_SSD_A1_SMB_CLK 
Z50_SSD_B1_SMB_CLK 
SSD_B1_SMB_OE 
SSD_A1_SMB_OE 
Z50_SSD_A1_SMB_CLK 
Z50_SSD_A1_SMB_DATA 
P3V3_DPB P3V3_DPB 
P3V3_DPB 
P1V8_PWR 
P3V3_DPB 
P1V8_PWR P1V8_PWR P1V8_PWR
P3V3_DPB P3V3_DPB 
P3V3_DPB 
P3V3_DPB 
P3V3_DPB 
P1V8_PWR 
P3V3_DPB 
P1V8_PWR 
P3V3_DPB P3V3_DPB P3V3_DPBP3V3_DPB 
P3V3_PWR P3V3_PWR 
Z50_SMB_DATA 5
Z50_SMB_CLK 5
Z50_SMB_CLK 5
Z50_SMB_DATA 5
Z50_SSD_A1_SMB_DATA 6
Z50_SSD_B1_SMB_CLK 6
Z50_SSD_A1_SMB_CLK 6
Z50_SSD_B1_SMB_DATA 6
Title 
Size Document Number Rev
Date: Sheet 
of 
Lightning_M.2_Adaptor_Card 1
Temp Sensor 
A3 
7 10Thursday, March 09, 2017 
Wiwynn 
H/W R&D Dept. II 
8F, 90, Sec.1, Xintai 5th Rd., Xizhi Dist.,
New Taipei City 22102, Taiwan (R.O.C.)
Title 
Size Document Number Rev
Date: Sheet 
of 
Lightning_M.2_Adaptor_Card 1
Temp Sensor 
A3 
7 10Thursday, March 09, 2017 
Wiwynn 
H/W R&D Dept. II 
8F, 90, Sec.1, Xintai 5th Rd., Xizhi Dist.,
New Taipei City 22102, Taiwan (R.O.C.)
Title 
Size Document Number Rev
Date: Sheet 
of 
Lightning_M.2_Adaptor_Card 1
Temp Sensor 
A3 
7 10Thursday, March 09, 2017 
Wiwynn 
H/W R&D Dept. II 
8F, 90, Sec.1, Xintai 5th Rd., Xizhi Dist.,
New Taipei City 22102, Taiwan (R.O.C.)
R12 
4K7R2F-GP 
1 2
C9 
SCD1U16V2KX-3GP 
1 2
R60 
47KR2F-GP 
NOPOP 
12
R61 0R2J-2-GP NOPOP 1 2
CN1 
CLX-CON3-S2-GP 
NOPOP 
1
2
3
R62 0R2J-2-GP NOPOP 1 2
R8 
4K7R2F-GP 
NOPOP 
1 2
R35 
47KR2F-GP 
NOPOP 
12
R31 
4K7R2F-GP 
1 2
U7 
TXS0102DCUR-1-GP 
B2 1
GND 2
VCCA 3
A2 4A1 5
OE 6
VCCB 7
B1 8
R5 
0R2J-2-GP 
1 2
R38 0R2J-2-GP 1 2
R57 
10KR2F-2-GP 
1 2
R10 
4K7R2F-GP 
NOPOP 
1 2
TP1 
1
R59 
47KR2F-GP 
NOPOP 
12
R39 0R2J-2-GP 1 2
R9 
0R2J-2-GP 
1 2
R28 
4K7R2F-GP 
1 2
R6 
4K7R2F-GP 
1 2
R32 
4K7R2F-GP 
12
R21 
4K7R2F-GP 
1 2
R41 0R2J-2-GP 1 2
R11 
4K7R2F-GP 
1 2
R36 
47KR2F-GP 
NOPOP 
12
R50 
47KR2F-GP 
NOPOP 
1 2
R29 
47KR2F-GP 
NOPOP 
12
C8 
SCD1U16V2KX-3GP 
1 2
R40 0R2J-2-GP 1 2
R53 33R2J-2-GP 1 2
U6 
TXS0102DCUR-1-GP 
B2 1
GND 2
VCCA 3
A2 4A1 5
OE 6
VCCB 7
B1 8
C11 
SCD1U16V2KX-3GP 
1 2
R54 
10KR2F-2-GP 
1 2
R27 
4K7R2F-GP 
NOPOP 
1 2
C39 
SCD1U16V2KX-3GP 
1 2
R51 
47KR2F-GP 
NOPOP 
1 2R64 0R2J-2-GP NOPOP 1 2
R56 33R2J-2-GP 1 2
R30 
47KR2F-GP 
NOPOP 
12
R7 
4K7R2F-GP 
NOPOP 
1 2
C10 
SCD1U16V2KX-3GP 
1 2
R55 33R2J-2-GP 1 2
R58 
47KR2F-GP 
NOPOP 
12
R34 
47KR2F-GP 
NOPOP 
12
C7 
SCD1U16V2KX-3GP 
1 2
R63 0R2J-2-GP NOPOP 1 2
U1 
TMP75AIDGKR-GP 
SDA 1
SCL 2
ALERT 3
GND 4 A2 5A1 6A0 7V+ 8
R52 33R2J-2-GP 1 2
U4 
PCA9543APW-GP 
A0 1
A1 2
RESET# 3
INT0# 4
VSS 7
INT1# 8
SD1 9
SC1 10 
INT# 11 
SCL 12 SDA 13 
VDD 14 SD0 5
SC0 6
R25 
4K7R2F-GP 
NOPOP 
1 2



5
5
4
4
3
3
2
2
1
1
D D
C C
B B
A A
TDC (include pull up resistor): 
M.2 Device*2=8.50281A 
10U/ X6S/0805 
FCCM Mode 
OCP = 11A 
SS=1.4ms 
FS=500KHz 
Power rail : P3V3_PWR 
Controller : TPS53319 (Fswitching=500KHz) 
TDC :8.502A 
MAX: 8.502A 
OCP : 11A 
Vout = 3.318V 
P3V3_DEV_VFB 
P3V3_DEV_PWRGD 
P3V3_DEV_ROVP 
P3V3_DEV_VREG 
P3V3_DEV_VIN 
P3V3_DEV_EN 
P3V3_DEV_LL 
P3V3_DEV_TRIP 
P3V3_DEV_VREG 
P3V3_DEV_VBST 
P3V3_DEV_MODE 
P3V3_DEV_VBST_RC 
P3V3_DEV_VDD 
P3V3_DEV_SNB 
P3V3_DEV_VFB_R 
P3V3_DEV_LL_R 
P3V3_DEV_RF 
P3V3_DEV_VREG 
P3V3_PWR 
AGND_P3V3_DEV 
P12V 
P12V 
AGND_P3V3_DEV 
AGND_P3V3_DEV 
AGND_P3V3_DEV 
AGND_P3V3_DEV 
P12V 
AGND_P3V3_DEV 
P3V3_PWR 
Title 
Size Document Number Rev
Date: Sheet 
of 
Lightning_M.2_Adaptor_Card 1
P3V3_PWR 
A3 
8 10Thursday, March 09, 2017 
Wiwynn 
H/W R&D Dept. II 
8F, 90, Sec.1, Xintai 5th Rd., Xizhi Dist.,
New Taipei City 22102, Taiwan (R.O.C.)
Title 
Size Document Number Rev
Date: Sheet 
of 
Lightning_M.2_Adaptor_Card 1
P3V3_PWR 
A3 
8 10Thursday, March 09, 2017 
Wiwynn 
H/W R&D Dept. II 
8F, 90, Sec.1, Xintai 5th Rd., Xizhi Dist.,
New Taipei City 22102, Taiwan (R.O.C.)
Title 
Size Document Number Rev
Date: Sheet 
of 
Lightning_M.2_Adaptor_Card 1
P3V3_PWR 
A3 
8 10Thursday, March 09, 2017 
Wiwynn 
H/W R&D Dept. II 
8F, 90, Sec.1, Xintai 5th Rd., Xizhi Dist.,
New Taipei City 22102, Taiwan (R.O.C.)
PC45 
ST150U6D3VDM-28-GP 
1 2
PG3 
COPPER-CLOSE-GP-U 
1 2
PR38 
0R3J-0-U-GP 
12
PC40 
SCD1U50V3KX-GP 
1 2
PR29 100KR2F-L1-GP 1 2
PC36 
SC4D7U25V5KX-1-GP 
1 2
PC30 
SC2K2P50V3KX-GP 
NOPOP 
1 2
PC43 
SC1KP50V2KX-1GP 
1 2
PR30 100KR2F-L1-GP NOPOP 1 2
PR37 
10KR2F-2-GP 
1 2
C267 
SC100P50V2JN-3GP 
NOPOP 
1 2
PC37 SC10U16V5KX-1-GP 
1 2
PC31 
SCD1U25V3KX-GP 
1 2
PC41 SCD1U25V2KX-2-GP 
1 2
PR39 
45K3R2F-L-GP 
1 2
PC42 
SC10U6D3V5KX-4GP 
1 2
PR27 
10R3F-GP 
1 2
PR31 121KR2F-L-GP 1 2
PR36 
0R2J-2-GP 
1 2
PR1 
37K4R2F-1-GP 
1 2
PC33 SC10U16V5KX-1-GP 
1 2
PR26 
2KR2F-3-GP 
1 2
PR28 
10KR2F-2-GP 
12
Notice:ZZ.53319.07301 
PU1 
TPS53319DQPR-GP 
VFB 1PGOOD 3
EN 2
VBST 4
ROVP 5
LL#6 6
LL#7 7
LL#8 8
LL#9 9
LL#10 10 
LL#11 11 
VIN 12 VIN 13 VIN 14 VIN 15 VIN 16 VIN 17 
VREG 18 
VDD 19 
MODE 20 
TRIP 21 
RF 22 
GND 23 
PC39 
SC10U6D3V5KX-4GP 
1 2
PC32 SC10U16V5KX-1-GP 
1 2
PC38 SC10U16V5KX-1-GP 
1 2
PL3 
IND-1D5UH-107-GP 
1 2
PC29 SC1U10V2KX-4-GP 
1 2
PR35 619KR2F-GP NOPOP 1 2
PL2 
BLM21PG220SN1DGP 
1 2
PR32 866KR2F-GP NOPOP 1 2
PR25 
10KR2F-2-GP 
12
PC34 SC10U16V5KX-1-GP 
1 2
TP2 
1
PC35 SC10U16V5KX-1-GP 
1 2
PR21 
2D2R3J-2-GP 
12
PR33 
3D01R5F-GP 
NOPOP 
1 2



5
5
4
4
3
3
2
2
1
1
D D
C C
B B
A A
Vout = 1.817V 
Power rail :P1V8_PWR(1.8V) 
Controller :TPS74801 
TDC :1.53mA 
Max :1.53mA 
OCP:2A 
TDC: 
Pull-up resistor:V/R=1.8/4.7K 
≒ 0.383mA 
Pull-up resistor *4 ≒ 1.53mA 
P1V8_PWR_BIAS 
P1V8_PWR_SS_C 
P1V8_PWR_EN_R 
P1V8_PWR_GD 
P1V8_PWR_FB 
P1V8_PWR_BIAS P1V8_PWR_GD 
P3V3_PWR 
P1V8_PWR 
P3V3_PWR 
P3V3_PWR 
P3V3_PWR 
Title 
Size Document Number Rev
Date: Sheet 
of 
Lightning_M.2_Adaptor_Card 1
P1V8_PWR 
A3 
9 10 Thursday, March 09, 2017 
Wiwynn 
H/W R&D Dept. II 
8F, 90, Sec.1, Xintai 5th Rd., Xizhi Dist.,
New Taipei City 22102, Taiwan (R.O.C.)
Title 
Size Document Number Rev
Date: Sheet 
of 
Lightning_M.2_Adaptor_Card 1
P1V8_PWR 
A3 
9 10 Thursday, March 09, 2017 
Wiwynn 
H/W R&D Dept. II 
8F, 90, Sec.1, Xintai 5th Rd., Xizhi Dist.,
New Taipei City 22102, Taiwan (R.O.C.)
Title 
Size Document Number Rev
Date: Sheet 
of 
Lightning_M.2_Adaptor_Card 1
P1V8_PWR 
A3 
9 10 Thursday, March 09, 2017 
Wiwynn 
H/W R&D Dept. II 
8F, 90, Sec.1, Xintai 5th Rd., Xizhi Dist.,
New Taipei City 22102, Taiwan (R.O.C.)
PC27 
SC22U6D3V5MX-5-GP 
1 2
PR20 
10KR2F-2-GP 
1 2
PR24 
0R3F-1-GP-U 
1 2
PU2 
TPS74801DRCR-1-GP-U 
IN#1 1
IN#2 2 PG 3
BIAS 4
EN 5
GND 6
SS 7
FB 8
OUT#9 9
OUT#10 10 
GND 11 
PR18 
0R2J-2-GP 
1 2
PC25 
SC22U6D3V5MX-5-GP 
1 2
TP5 
1
PC23 
SC4D7U16V5KX-1-GP 
1 2
PC24 
SC22U6D3V5MX-5-GP 
1 2
PC26 
SC10U6D3V5KX-4GP 
1 2
PR22 
3K65R2F-1-GP 1 2
PC20 
SCD01U25V2KX-3GP 
1 2
PC21 
SC820P50V2KX-1GP 
1 2
PC28 
SC1KP50V2KX-1GP 
1 2
PR23 
2K87R2F-1-GP 
1 2
PC22 
SCD01U25V2KX-3GP 
NOPOP
1 2